# T6G (Grand Teton) — schematic netlist excerpt (pin names and nets, part order shuffled) for the footprints in the layout excerpt that follows; sources: Cadence DE-HDL packaged netlist, KiCad conversion of 04192023_DAF0TMB3IC0_F0TG_MB_C_brd_V02_OCP.brd

PC180  Q_CAP  560PF 50V 10% EMPTY  pkg C0402  page 195 : A = SW_PVDDCR_CPU0_P0_SW3 ; B = SW_PVDDCR_CPU0_P0_SW3_RC

(kicad_pcb
	(version 20260206)
	(generator "pcbnew")
	(generator_version "10.0")
	(general
		(thickness 1.6)
		(legacy_teardrops no)
	)
	(paper "A4")
	(title_block
		(title "04192023_DAF0TMB3IC0_F0TG_MB_C_brd_V02_OCP.brd")
		(comment 1 "Grand Teton / footprints 1807-1807 of 8354")
	)
	(layers
		(0 "F.Cu" signal "TOP")
		(4 "In1.Cu" signal "GND")
		(6 "In2.Cu" signal "IN1")
		(8 "In3.Cu" signal "GND1")
		(10 "In4.Cu" signal "IN2")
		(12 "In5.Cu" signal "GND2")
		(14 "In6.Cu" signal "IN3")
		(16 "In7.Cu" signal "GND3")
		(18 "In8.Cu" signal "VCC")
		(20 "In9.Cu" signal "VCC1")
		(22 "In10.Cu" signal "GND4")
		(24 "In11.Cu" signal "IN4")
		(26 "In12.Cu" signal "GND5")
		(28 "In13.Cu" signal "IN5")
		(30 "In14.Cu" signal "GND6")
		(32 "In15.Cu" signal "IN6")
		(34 "In16.Cu" signal "GND7")
		(2 "B.Cu" signal "BOTTOM")
		(9 "F.Adhes" user "F.Adhesive")
		(11 "B.Adhes" user "B.Adhesive")
		(13 "F.Paste" user "Package Geometry/Pastemask Top")
		(15 "B.Paste" user "Package Geometry/Pastemask Bottom")
		(5 "F.SilkS" user "Ref Des/Silkscreen Top")
		(7 "B.SilkS" user "Ref Des/Silkscreen Bottom")
		(1 "F.Mask" user "Board Geometry/Soldermask Top")
		(3 "B.Mask" user "Board Geometry/Soldermask Bottom")
		(17 "Dwgs.User" user "User.Drawings")
		(19 "Cmts.User" user "User.Comments")
		(21 "Eco1.User" user "User.Eco1")
		(23 "Eco2.User" user "User.Eco2")
		(25 "Edge.Cuts" user "Board Geometry/Outline")
		(27 "Margin" user)
		(31 "F.CrtYd" user "Package Geometry/Place Bound Top")
		(29 "B.CrtYd" user "Package Geometry/Place Bound Bottom")
		(35 "F.Fab" user "Ref Des/Assembly Top")
		(33 "B.Fab" user "Ref Des/Assembly Bottom")
	)
	(footprint ""
		(layer "F.Cu")
		(at 384.7719 -185.748168)
		(property "Reference" "PC180"
			(at 0 0 0)
			(layer "F.SilkS")
			(hide yes)
			(effects
				(font
					(size 1.27 1.27)
				)
			)
		)
		(property "Value" ""
			(at 0 0 0)
			(layer "F.Fab")
			(effects
				(font
					(size 1.27 1.27)
				)
			)
		)
		(duplicate_pad_numbers_are_jumpers no)
		(fp_line
			(start -0.7874 -0.4064)
			(end 0.7874 -0.4064)
			(stroke
				(width 0.1524)
				(type default)
			)
			(layer "F.SilkS")
		)
		(fp_line
			(start -0.7874 0.4064)
			(end -0.7874 -0.4064)
			(stroke
				(width 0.1524)
				(type default)
			)
			(layer "F.SilkS")
		)
		(fp_line
			(start 0.7874 -0.4064)
			(end 0.7874 0.4064)
			(stroke
				(width 0.1524)
				(type default)
			)
			(layer "F.SilkS")
		)
		(fp_line
			(start 0.7874 0.4064)
			(end -0.7874 0.4064)
			(stroke
				(width 0.1524)
				(type default)
			)
			(layer "F.SilkS")
		)
		(fp_line
			(start -0.67945 -0.305054)
			(end -0.12065 -0.305054)
			(stroke
				(width 0.1)
				(type default)
			)
			(layer "F.Fab")
		)
		(fp_line
			(start -0.67945 0.3048)
			(end -0.67945 -0.305054)
			(stroke
				(width 0.1)
				(type default)
			)
			(layer "F.Fab")
		)
		(fp_line
			(start -0.12065 -0.305054)
			(end -0.12065 -0.2794)
			(stroke
				(width 0.1)
				(type default)
			)
			(layer "F.Fab")
		)
		(fp_line
			(start -0.12065 -0.2794)
			(end 0.12065 -0.2794)
			(stroke
				(width 0.1)
				(type default)
			)
			(layer "F.Fab")
		)
		(fp_line
			(start -0.12065 0.2794)
			(end -0.12065 0.3048)
			(stroke
				(width 0.1)
				(type default)
			)
			(layer "F.Fab")
		)
		(fp_line
			(start -0.12065 0.3048)
			(end -0.67945 0.3048)
			(stroke
				(width 0.1)
				(type default)
			)
			(layer "F.Fab")
		)
		(fp_line
			(start 0.120396 0.2794)
			(end -0.12065 0.2794)
			(stroke
				(width 0.1)
				(type default)
			)
			(layer "F.Fab")
		)
		(fp_line
			(start 0.120396 0.3048)
			(end 0.120396 0.2794)
			(stroke
				(width 0.1)
				(type default)
			)
			(layer "F.Fab")
		)
		(fp_line
			(start 0.12065 -0.3048)
			(end 0.67945 -0.3048)
			(stroke
				(width 0.1)
				(type default)
			)
			(layer "F.Fab")
		)
		(fp_line
			(start 0.12065 -0.2794)
			(end 0.12065 -0.3048)
			(stroke
				(width 0.1)
				(type default)
			)
			(layer "F.Fab")
		)
		(fp_line
			(start 0.67945 -0.3048)
			(end 0.67945 0.3048)
			(stroke
				(width 0.1)
				(type default)
			)
			(layer "F.Fab")
		)
		(fp_line
			(start 0.67945 0.3048)
			(end 0.120396 0.3048)
			(stroke
				(width 0.1)
				(type default)
			)
			(layer "F.Fab")
		)
		(pad "1" smd circle
			(at -0.40005 0)
			(size 0 0)
			(layers "F.Cu" "F.Mask" "F.Paste")
			(net "SW_PVDDCR_CPU0_P0_SW3")
		)
		(pad "2" smd circle
			(at 0.40005 0)
			(size 0 0)
			(layers "F.Cu" "F.Mask" "F.Paste")
			(net "SW_PVDDCR_CPU0_P0_SW3_RC")
		)
	)
)
